# S9S_MB_2U (Grand Teton) — schematic netlist excerpt (pin names and nets, part order shuffled) for the footprints in the layout excerpt that follows; sources: Cadence DE-HDL packaged netlist, KiCad conversion of 03242023_DA0F0TMBIJ0_F0T_Motherboard_J_brd_V01_OCP.brd

R3776  Q_RES  0 5% CHIP  pkg 0402LF  page 240 : A = FM_UARTSW_MSB_N ; B = FM_UARTSW_MSB_R
C1909  Q_CAP  0.01UF 50V 10% X7R  pkg C0402  page 217 : A = P3V3_AUX_FPGA_VCCIO2 ; B = GND

(kicad_pcb
	(version 20260206)
	(generator "pcbnew")
	(generator_version "10.0")
	(general
		(thickness 1.6)
		(legacy_teardrops no)
	)
	(paper "A4")
	(title_block
		(title "03242023_DA0F0TMBIJ0_F0T_Motherboard_J_brd_V01_OCP.brd")
		(comment 1 "Grand Teton / footprints 5637-5638 of 6105")
	)
	(layers
		(0 "F.Cu" signal "TOP")
		(4 "In1.Cu" signal "GND")
		(6 "In2.Cu" signal "IN1")
		(8 "In3.Cu" signal "GND1")
		(10 "In4.Cu" signal "IN2")
		(12 "In5.Cu" signal "GND2")
		(14 "In6.Cu" signal "IN3")
		(16 "In7.Cu" signal "GND3")
		(18 "In8.Cu" signal "VCC")
		(20 "In9.Cu" signal "VCC1")
		(22 "In10.Cu" signal "GND4")
		(24 "In11.Cu" signal "IN4")
		(26 "In12.Cu" signal "GND5")
		(28 "In13.Cu" signal "IN5")
		(30 "In14.Cu" signal "GND6")
		(32 "In15.Cu" signal "IN6")
		(34 "In16.Cu" signal "GND7")
		(2 "B.Cu" signal "BOTTOM")
		(9 "F.Adhes" user "F.Adhesive")
		(11 "B.Adhes" user "B.Adhesive")
		(13 "F.Paste" user "Package Geometry/Pastemask Top")
		(15 "B.Paste" user "Package Geometry/Pastemask Bottom")
		(5 "F.SilkS" user "Ref Des/Silkscreen Top")
		(7 "B.SilkS" user "Ref Des/Silkscreen Bottom")
		(1 "F.Mask" user "Board Geometry/Soldermask Top")
		(3 "B.Mask" user "Board Geometry/Soldermask Bottom")
		(17 "Dwgs.User" user "User.Drawings")
		(19 "Cmts.User" user "User.Comments")
		(21 "Eco1.User" user "User.Eco1")
		(23 "Eco2.User" user "User.Eco2")
		(25 "Edge.Cuts" user "Board Geometry/Outline")
		(27 "Margin" user)
		(31 "F.CrtYd" user "Package Geometry/Place Bound Top")
		(29 "B.CrtYd" user "Package Geometry/Place Bound Bottom")
		(35 "F.Fab" user "Ref Des/Assembly Top")
		(33 "B.Fab" user "Ref Des/Assembly Bottom")
	)
	(footprint ""
		(layer "B.Cu")
		(at 185.755788 -109.775498 180)
		(property "Reference" "C1909"
			(at 0 0 0)
			(layer "B.SilkS")
			(hide yes)
			(effects
				(font
					(size 1.27 1.27)
				)
				(justify mirror)
			)
		)
		(property "Value" ""
			(at 0 0 0)
			(layer "B.Fab")
			(effects
				(font
					(size 1.27 1.27)
				)
				(justify mirror)
			)
		)
		(duplicate_pad_numbers_are_jumpers no)
		(fp_line
			(start 0.69215 0.2921)
			(end 0.69215 -0.2921)
			(stroke
				(width 0.1524)
				(type default)
			)
			(layer "B.SilkS")
		)
		(fp_line
			(start 0.69215 -0.2921)
			(end -0.69215 -0.2921)
			(stroke
				(width 0.1524)
				(type default)
			)
			(layer "B.SilkS")
		)
		(fp_line
			(start -0.69215 0.2921)
			(end 0.69215 0.2921)
			(stroke
				(width 0.1524)
				(type default)
			)
			(layer "B.SilkS")
		)
		(fp_line
			(start -0.69215 -0.2921)
			(end -0.69215 0.2921)
			(stroke
				(width 0.1524)
				(type default)
			)
			(layer "B.SilkS")
		)
		(fp_line
			(start 0.51435 0.2794)
			(end 0.51435 -0.2794)
			(stroke
				(width 0.1)
				(type default)
			)
			(layer "B.Fab")
		)
		(fp_line
			(start 0.51435 -0.2794)
			(end -0.51435 -0.2794)
			(stroke
				(width 0.1)
				(type default)
			)
			(layer "B.Fab")
		)
		(fp_line
			(start -0.51435 0.2794)
			(end 0.51435 0.2794)
			(stroke
				(width 0.1)
				(type default)
			)
			(layer "B.Fab")
		)
		(fp_line
			(start -0.51435 -0.2794)
			(end -0.51435 0.2794)
			(stroke
				(width 0.1)
				(type default)
			)
			(layer "B.Fab")
		)
		(pad "1" smd circle
			(at 0.40005 0)
			(size 0 0)
			(layers "B.Cu" "B.Mask" "B.Paste")
			(net "P3V3_AUX_FPGA_VCCIO2")
		)
		(pad "2" smd circle
			(at -0.40005 0)
			(size 0 0)
			(layers "B.Cu" "B.Mask" "B.Paste")
			(net "GND")
		)
		(zone
			(layer "B.Cu")
			(hatch none 0.5)
			(connect_pads
				(clearance 0)
			)
			(min_thickness 0.25)
			(keepout
				(tracks not_allowed)
				(vias allowed)
				(pads allowed)
				(copperpour not_allowed)
				(footprints allowed)
			)
			(placement
				(enabled no)
				(sheetname "")
			)
			(fill
				(thermal_gap 0.5)
				(thermal_bridge_width 0.5)
				(island_removal_mode 0)
			)
			(polygon
				(pts
					(xy 185.565288 -109.863128) (xy 185.656728 -109.921294) (xy 185.856118 -109.921294) (xy 185.946288 -109.863128)
					(xy 185.946288 -109.687868) (xy 185.856118 -109.629448) (xy 185.656728 -109.629448) (xy 185.565288 -109.687614)
				)
			)
		)
	)
	(footprint ""
		(layer "B.Cu")
		(at 135.81888 -9.362948 -90)
		(property "Reference" "R3776"
			(at 0 0 90)
			(layer "B.SilkS")
			(hide yes)
			(effects
				(font
					(size 1.27 1.27)
				)
				(justify mirror)
			)
		)
		(property "Value" ""
			(at 0 0 90)
			(layer "B.Fab")
			(effects
				(font
					(size 1.27 1.27)
				)
				(justify mirror)
			)
		)
		(duplicate_pad_numbers_are_jumpers no)
		(fp_line
			(start -0.7874 0.4064)
			(end 0.7874 0.4064)
			(stroke
				(width 0.1524)
				(type default)
			)
			(layer "B.SilkS")
		)
		(fp_line
			(start 0.7874 0.4064)
			(end 0.7874 -0.4064)
			(stroke
				(width 0.1524)
				(type default)
			)
			(layer "B.SilkS")
		)
		(fp_line
			(start -0.7874 -0.4064)
			(end -0.7874 0.4064)
			(stroke
				(width 0.1524)
				(type default)
			)
			(layer "B.SilkS")
		)
		(fp_line
			(start 0.7874 -0.4064)
			(end -0.7874 -0.4064)
			(stroke
				(width 0.1524)
				(type default)
			)
			(layer "B.SilkS")
		)
		(fp_line
			(start -0.67945 0.3048)
			(end -0.120396 0.3048)
			(stroke
				(width 0.1)
				(type default)
			)
			(layer "B.Fab")
		)
		(fp_line
			(start -0.120396 0.3048)
			(end -0.120396 0.2794)
			(stroke
				(width 0.1)
				(type default)
			)
			(layer "B.Fab")
		)
		(fp_line
			(start 0.12065 0.3048)
			(end 0.67945 0.3048)
			(stroke
				(width 0.1)
				(type default)
			)
			(layer "B.Fab")
		)
		(fp_line
			(start 0.67945 0.3048)
			(end 0.67945 -0.305054)
			(stroke
				(width 0.1)
				(type default)
			)
			(layer "B.Fab")
		)
		(fp_line
			(start -0.120396 0.2794)
			(end 0.12065 0.2794)
			(stroke
				(width 0.1)
				(type default)
			)
			(layer "B.Fab")
		)
		(fp_line
			(start 0.12065 0.2794)
			(end 0.12065 0.3048)
			(stroke
				(width 0.1)
				(type default)
			)
			(layer "B.Fab")
		)
		(fp_line
			(start -0.12065 -0.2794)
			(end -0.12065 -0.3048)
			(stroke
				(width 0.1)
				(type default)
			)
			(layer "B.Fab")
		)
		(fp_line
			(start 0.12065 -0.2794)
			(end -0.12065 -0.2794)
			(stroke
				(width 0.1)
				(type default)
			)
			(layer "B.Fab")
		)
		(fp_line
			(start -0.67945 -0.3048)
			(end -0.67945 0.3048)
			(stroke
				(width 0.1)
				(type default)
			)
			(layer "B.Fab")
		)
		(fp_line
			(start -0.12065 -0.3048)
			(end -0.67945 -0.3048)
			(stroke
				(width 0.1)
				(type default)
			)
			(layer "B.Fab")
		)
		(fp_line
			(start 0.12065 -0.305054)
			(end 0.12065 -0.2794)
			(stroke
				(width 0.1)
				(type default)
			)
			(layer "B.Fab")
		)
		(fp_line
			(start 0.67945 -0.305054)
			(end 0.12065 -0.305054)
			(stroke
				(width 0.1)
				(type default)
			)
			(layer "B.Fab")
		)
		(pad "1" smd circle
			(at 0.40005 0 90)
			(size 0 0)
			(layers "B.Cu" "B.Mask" "B.Paste")
			(net "FM_UARTSW_MSB_N")
		)
		(pad "2" smd circle
			(at -0.40005 0 90)
			(size 0 0)
			(layers "B.Cu" "B.Mask" "B.Paste")
			(net "FM_UARTSW_MSB_R")
		)
	)
)
